(kicad_pcb
	(version 20260206)
	(generator "pcbnew")
	(generator_version "10.0")
	(general
		(thickness 1.6)
		(legacy_teardrops no)
	)
	(paper "A4")
	(title_block
		(title "03242023_DA0F0TMBIJ0_F0T_Motherboard_J_brd_V01_OCP.brd")
		(comment 1 "Grand Teton / footprints 5093-5098 of 6105")
	)
	(layers
		(0 "F.Cu" signal "TOP")
		(4 "In1.Cu" signal "GND")
		(6 "In2.Cu" signal "IN1")
		(8 "In3.Cu" signal "GND1")
		(10 "In4.Cu" signal "IN2")
		(12 "In5.Cu" signal "GND2")
		(14 "In6.Cu" signal "IN3")
		(16 "In7.Cu" signal "GND3")
		(18 "In8.Cu" signal "VCC")
		(20 "In9.Cu" signal "VCC1")
		(22 "In10.Cu" signal "GND4")
		(24 "In11.Cu" signal "IN4")
		(26 "In12.Cu" signal "GND5")
		(28 "In13.Cu" signal "IN5")
		(30 "In14.Cu" signal "GND6")
		(32 "In15.Cu" signal "IN6")
		(34 "In16.Cu" signal "GND7")
		(2 "B.Cu" signal "BOTTOM")
		(9 "F.Adhes" user "F.Adhesive")
		(11 "B.Adhes" user "B.Adhesive")
		(13 "F.Paste" user "Package Geometry/Pastemask Top")
		(15 "B.Paste" user "Package Geometry/Pastemask Bottom")
		(5 "F.SilkS" user "Ref Des/Silkscreen Top")
		(7 "B.SilkS" user "Ref Des/Silkscreen Bottom")
		(1 "F.Mask" user "Board Geometry/Soldermask Top")
		(3 "B.Mask" user "Board Geometry/Soldermask Bottom")
		(17 "Dwgs.User" user "User.Drawings")
		(19 "Cmts.User" user "User.Comments")
		(21 "Eco1.User" user "User.Eco1")
		(23 "Eco2.User" user "User.Eco2")
		(25 "Edge.Cuts" user "Board Geometry/Outline")
		(27 "Margin" user)
		(31 "F.CrtYd" user "Package Geometry/Place Bound Top")
		(29 "B.CrtYd" user "Package Geometry/Place Bound Bottom")
		(35 "F.Fab" user "Ref Des/Assembly Top")
		(33 "B.Fab" user "Ref Des/Assembly Bottom")
	)
	(footprint ""
		(layer "B.Cu")
		(at 178.145948 -192.699894 -90)
		(property "Reference" "R267"
			(at 0 0 90)
			(layer "B.SilkS")
			(hide yes)
			(effects
				(font
					(size 1.27 1.27)
				)
				(justify mirror)
			)
		)
		(property "Value" ""
			(at 0 0 90)
			(layer "B.Fab")
			(effects
				(font
					(size 1.27 1.27)
				)
				(justify mirror)
			)
		)
		(duplicate_pad_numbers_are_jumpers no)
		(fp_line
			(start -0.7874 0.4064)
			(end 0.7874 0.4064)
			(stroke
				(width 0.1524)
				(type default)
			)
			(layer "B.SilkS")
		)
		(fp_line
			(start 0.7874 0.4064)
			(end 0.7874 -0.4064)
			(stroke
				(width 0.1524)
				(type default)
			)
			(layer "B.SilkS")
		)
		(fp_line
			(start -0.7874 -0.4064)
			(end -0.7874 0.4064)
			(stroke
				(width 0.1524)
				(type default)
			)
			(layer "B.SilkS")
		)
		(fp_line
			(start 0.7874 -0.4064)
			(end -0.7874 -0.4064)
			(stroke
				(width 0.1524)
				(type default)
			)
			(layer "B.SilkS")
		)
		(fp_line
			(start -0.67945 0.3048)
			(end -0.120396 0.3048)
			(stroke
				(width 0.1)
				(type default)
			)
			(layer "B.Fab")
		)
		(fp_line
			(start -0.120396 0.3048)
			(end -0.120396 0.2794)
			(stroke
				(width 0.1)
				(type default)
			)
			(layer "B.Fab")
		)
		(fp_line
			(start 0.12065 0.3048)
			(end 0.67945 0.3048)
			(stroke
				(width 0.1)
				(type default)
			)
			(layer "B.Fab")
		)
		(fp_line
			(start 0.67945 0.3048)
			(end 0.67945 -0.305054)
			(stroke
				(width 0.1)
				(type default)
			)
			(layer "B.Fab")
		)
		(fp_line
			(start -0.120396 0.2794)
			(end 0.12065 0.2794)
			(stroke
				(width 0.1)
				(type default)
			)
			(layer "B.Fab")
		)
		(fp_line
			(start 0.12065 0.2794)
			(end 0.12065 0.3048)
			(stroke
				(width 0.1)
				(type default)
			)
			(layer "B.Fab")
		)
		(fp_line
			(start -0.12065 -0.2794)
			(end -0.12065 -0.3048)
			(stroke
				(width 0.1)
				(type default)
			)
			(layer "B.Fab")
		)
		(fp_line
			(start 0.12065 -0.2794)
			(end -0.12065 -0.2794)
			(stroke
				(width 0.1)
				(type default)
			)
			(layer "B.Fab")
		)
		(fp_line
			(start -0.67945 -0.3048)
			(end -0.67945 0.3048)
			(stroke
				(width 0.1)
				(type default)
			)
			(layer "B.Fab")
		)
		(fp_line
			(start -0.12065 -0.3048)
			(end -0.67945 -0.3048)
			(stroke
				(width 0.1)
				(type default)
			)
			(layer "B.Fab")
		)
		(fp_line
			(start 0.12065 -0.305054)
			(end 0.12065 -0.2794)
			(stroke
				(width 0.1)
				(type default)
			)
			(layer "B.Fab")
		)
		(fp_line
			(start 0.67945 -0.305054)
			(end 0.12065 -0.305054)
			(stroke
				(width 0.1)
				(type default)
			)
			(layer "B.Fab")
		)
		(pad "1" smd circle
			(at 0.40005 0 90)
			(size 0 0)
			(layers "B.Cu" "B.Mask" "B.Paste")
			(net "PVNN_TERM_CPU1")
		)
		(pad "2" smd circle
			(at -0.40005 0 90)
			(size 0 0)
			(layers "B.Cu" "B.Mask" "B.Paste")
			(net "PU_CPU1_SOCKET_ID2")
		)
	)
	(footprint ""
		(layer "B.Cu")
		(at 337.641692 -137.832338 180)
		(property "Reference" "R1020"
			(at 0 0 0)
			(layer "B.SilkS")
			(hide yes)
			(effects
				(font
					(size 1.27 1.27)
				)
				(justify mirror)
			)
		)
		(property "Value" ""
			(at 0 0 0)
			(layer "B.Fab")
			(effects
				(font
					(size 1.27 1.27)
				)
				(justify mirror)
			)
		)
		(duplicate_pad_numbers_are_jumpers no)
		(fp_line
			(start 0.7874 0.4064)
			(end 0.7874 0.05207)
			(stroke
				(width 0.1524)
				(type default)
			)
			(layer "B.SilkS")
		)
		(fp_line
			(start 0.515112 -0.4064)
			(end -0.518668 -0.4064)
			(stroke
				(width 0.1524)
				(type default)
			)
			(layer "B.SilkS")
		)
		(fp_line
			(start -0.7874 0.4064)
			(end 0.7874 0.4064)
			(stroke
				(width 0.1524)
				(type default)
			)
			(layer "B.SilkS")
		)
		(fp_line
			(start -0.7874 -0.09017)
			(end -0.7874 0.4064)
			(stroke
				(width 0.1524)
				(type default)
			)
			(layer "B.SilkS")
		)
		(fp_line
			(start 0.67945 0.3048)
			(end 0.67945 -0.305054)
			(stroke
				(width 0.1)
				(type default)
			)
			(layer "B.Fab")
		)
		(fp_line
			(start 0.67945 -0.305054)
			(end 0.12065 -0.305054)
			(stroke
				(width 0.1)
				(type default)
			)
			(layer "B.Fab")
		)
		(fp_line
			(start 0.12065 0.3048)
			(end 0.67945 0.3048)
			(stroke
				(width 0.1)
				(type default)
			)
			(layer "B.Fab")
		)
		(fp_line
			(start 0.12065 0.2794)
			(end 0.12065 0.3048)
			(stroke
				(width 0.1)
				(type default)
			)
			(layer "B.Fab")
		)
		(fp_line
			(start 0.12065 -0.2794)
			(end -0.12065 -0.2794)
			(stroke
				(width 0.1)
				(type default)
			)
			(layer "B.Fab")
		)
		(fp_line
			(start 0.12065 -0.305054)
			(end 0.12065 -0.2794)
			(stroke
				(width 0.1)
				(type default)
			)
			(layer "B.Fab")
		)
		(fp_line
			(start -0.120396 0.3048)
			(end -0.120396 0.2794)
			(stroke
				(width 0.1)
				(type default)
			)
			(layer "B.Fab")
		)
		(fp_line
			(start -0.120396 0.2794)
			(end 0.12065 0.2794)
			(stroke
				(width 0.1)
				(type default)
			)
			(layer "B.Fab")
		)
		(fp_line
			(start -0.12065 -0.2794)
			(end -0.12065 -0.3048)
			(stroke
				(width 0.1)
				(type default)
			)
			(layer "B.Fab")
		)
		(fp_line
			(start -0.12065 -0.3048)
			(end -0.67945 -0.3048)
			(stroke
				(width 0.1)
				(type default)
			)
			(layer "B.Fab")
		)
		(fp_line
			(start -0.67945 0.3048)
			(end -0.120396 0.3048)
			(stroke
				(width 0.1)
				(type default)
			)
			(layer "B.Fab")
		)
		(fp_line
			(start -0.67945 -0.3048)
			(end -0.67945 0.3048)
			(stroke
				(width 0.1)
				(type default)
			)
			(layer "B.Fab")
		)
		(pad "1" smd rect
			(at 0.40005 0 180)
			(size 0.4572 0.508)
			(layers "B.Cu" "B.Mask" "B.Paste")
			(net "CLK_25M_CK440_CPU0_R_DP")
		)
		(pad "2" smd rect
			(at -0.40005 0 180)
			(size 0.4572 0.508)
			(layers "B.Cu" "B.Mask" "B.Paste")
			(net "CLK_25M_NSSC_CPU0_DP")
		)
	)
	(footprint ""
		(layer "B.Cu")
		(at 259.097526 -76.558902 -90)
		(property "Reference" "PR1649"
			(at 0 0 90)
			(layer "B.SilkS")
			(hide yes)
			(effects
				(font
					(size 1.27 1.27)
				)
				(justify mirror)
			)
		)
		(property "Value" ""
			(at 0 0 90)
			(layer "B.Fab")
			(effects
				(font
					(size 1.27 1.27)
				)
				(justify mirror)
			)
		)
		(duplicate_pad_numbers_are_jumpers no)
		(fp_line
			(start -0.7874 0.4064)
			(end 0.7874 0.4064)
			(stroke
				(width 0.1524)
				(type default)
			)
			(layer "B.SilkS")
		)
		(fp_line
			(start 0.7874 0.4064)
			(end 0.7874 -0.4064)
			(stroke
				(width 0.1524)
				(type default)
			)
			(layer "B.SilkS")
		)
		(fp_line
			(start -0.7874 -0.4064)
			(end -0.7874 0.4064)
			(stroke
				(width 0.1524)
				(type default)
			)
			(layer "B.SilkS")
		)
		(fp_line
			(start 0.7874 -0.4064)
			(end -0.7874 -0.4064)
			(stroke
				(width 0.1524)
				(type default)
			)
			(layer "B.SilkS")
		)
		(fp_line
			(start -0.67945 0.3048)
			(end -0.120396 0.3048)
			(stroke
				(width 0.1)
				(type default)
			)
			(layer "B.Fab")
		)
		(fp_line
			(start -0.120396 0.3048)
			(end -0.120396 0.2794)
			(stroke
				(width 0.1)
				(type default)
			)
			(layer "B.Fab")
		)
		(fp_line
			(start 0.12065 0.3048)
			(end 0.67945 0.3048)
			(stroke
				(width 0.1)
				(type default)
			)
			(layer "B.Fab")
		)
		(fp_line
			(start 0.67945 0.3048)
			(end 0.67945 -0.305054)
			(stroke
				(width 0.1)
				(type default)
			)
			(layer "B.Fab")
		)
		(fp_line
			(start -0.120396 0.2794)
			(end 0.12065 0.2794)
			(stroke
				(width 0.1)
				(type default)
			)
			(layer "B.Fab")
		)
		(fp_line
			(start 0.12065 0.2794)
			(end 0.12065 0.3048)
			(stroke
				(width 0.1)
				(type default)
			)
			(layer "B.Fab")
		)
		(fp_line
			(start -0.12065 -0.2794)
			(end -0.12065 -0.3048)
			(stroke
				(width 0.1)
				(type default)
			)
			(layer "B.Fab")
		)
		(fp_line
			(start 0.12065 -0.2794)
			(end -0.12065 -0.2794)
			(stroke
				(width 0.1)
				(type default)
			)
			(layer "B.Fab")
		)
		(fp_line
			(start -0.67945 -0.3048)
			(end -0.67945 0.3048)
			(stroke
				(width 0.1)
				(type default)
			)
			(layer "B.Fab")
		)
		(fp_line
			(start -0.12065 -0.3048)
			(end -0.67945 -0.3048)
			(stroke
				(width 0.1)
				(type default)
			)
			(layer "B.Fab")
		)
		(fp_line
			(start 0.12065 -0.305054)
			(end 0.12065 -0.2794)
			(stroke
				(width 0.1)
				(type default)
			)
			(layer "B.Fab")
		)
		(fp_line
			(start 0.67945 -0.305054)
			(end 0.12065 -0.305054)
			(stroke
				(width 0.1)
				(type default)
			)
			(layer "B.Fab")
		)
		(pad "1" smd circle
			(at 0.40005 0 90)
			(size 0 0)
			(layers "B.Cu" "B.Mask" "B.Paste")
			(net "FM_P1V05_PCH_AUX_R_EN")
		)
		(pad "2" smd circle
			(at -0.40005 0 90)
			(size 0 0)
			(layers "B.Cu" "B.Mask" "B.Paste")
			(net "GND")
		)
	)
	(footprint ""
		(layer "B.Cu")
		(at 266.065 -98.008948 -90)
		(property "Reference" "C107"
			(at 0 0 90)
			(layer "B.SilkS")
			(hide yes)
			(effects
				(font
					(size 1.27 1.27)
				)
				(justify mirror)
			)
		)
		(property "Value" ""
			(at 0 0 90)
			(layer "B.Fab")
			(effects
				(font
					(size 1.27 1.27)
				)
				(justify mirror)
			)
		)
		(duplicate_pad_numbers_are_jumpers no)
		(fp_line
			(start -0.7874 0.4064)
			(end 0.7874 0.4064)
			(stroke
				(width 0.1524)
				(type default)
			)
			(layer "B.SilkS")
		)
		(fp_line
			(start 0.7874 0.4064)
			(end 0.7874 -0.4064)
			(stroke
				(width 0.1524)
				(type default)
			)
			(layer "B.SilkS")
		)
		(fp_line
			(start -0.7874 -0.4064)
			(end -0.7874 0.4064)
			(stroke
				(width 0.1524)
				(type default)
			)
			(layer "B.SilkS")
		)
		(fp_line
			(start 0.7874 -0.4064)
			(end -0.7874 -0.4064)
			(stroke
				(width 0.1524)
				(type default)
			)
			(layer "B.SilkS")
		)
		(fp_line
			(start -0.67945 0.3048)
			(end -0.120396 0.3048)
			(stroke
				(width 0.1)
				(type default)
			)
			(layer "B.Fab")
		)
		(fp_line
			(start -0.120396 0.3048)
			(end -0.120396 0.2794)
			(stroke
				(width 0.1)
				(type default)
			)
			(layer "B.Fab")
		)
		(fp_line
			(start 0.12065 0.3048)
			(end 0.67945 0.3048)
			(stroke
				(width 0.1)
				(type default)
			)
			(layer "B.Fab")
		)
		(fp_line
			(start 0.67945 0.3048)
			(end 0.67945 -0.305054)
			(stroke
				(width 0.1)
				(type default)
			)
			(layer "B.Fab")
		)
		(fp_line
			(start -0.120396 0.2794)
			(end 0.12065 0.2794)
			(stroke
				(width 0.1)
				(type default)
			)
			(layer "B.Fab")
		)
		(fp_line
			(start 0.12065 0.2794)
			(end 0.12065 0.3048)
			(stroke
				(width 0.1)
				(type default)
			)
			(layer "B.Fab")
		)
		(fp_line
			(start -0.12065 -0.2794)
			(end -0.12065 -0.3048)
			(stroke
				(width 0.1)
				(type default)
			)
			(layer "B.Fab")
		)
		(fp_line
			(start 0.12065 -0.2794)
			(end -0.12065 -0.2794)
			(stroke
				(width 0.1)
				(type default)
			)
			(layer "B.Fab")
		)
		(fp_line
			(start -0.67945 -0.3048)
			(end -0.67945 0.3048)
			(stroke
				(width 0.1)
				(type default)
			)
			(layer "B.Fab")
		)
		(fp_line
			(start -0.12065 -0.3048)
			(end -0.67945 -0.3048)
			(stroke
				(width 0.1)
				(type default)
			)
			(layer "B.Fab")
		)
		(fp_line
			(start 0.12065 -0.305054)
			(end 0.12065 -0.2794)
			(stroke
				(width 0.1)
				(type default)
			)
			(layer "B.Fab")
		)
		(fp_line
			(start 0.67945 -0.305054)
			(end 0.12065 -0.305054)
			(stroke
				(width 0.1)
				(type default)
			)
			(layer "B.Fab")
		)
		(pad "1" smd circle
			(at 0.40005 0 90)
			(size 0 0)
			(layers "B.Cu" "B.Mask" "B.Paste")
			(net "P3V3_AUX_CLK_GEN_VDD_CK440")
		)
		(pad "2" smd circle
			(at -0.40005 0 90)
			(size 0 0)
			(layers "B.Cu" "B.Mask" "B.Paste")
			(net "GND")
		)
	)
	(footprint ""
		(layer "B.Cu")
		(at 236.201712 -135.401558 180)
		(property "Reference" "R1023"
			(at 0 0 0)
			(layer "B.SilkS")
			(hide yes)
			(effects
				(font
					(size 1.27 1.27)
				)
				(justify mirror)
			)
		)
		(property "Value" ""
			(at 0 0 0)
			(layer "B.Fab")
			(effects
				(font
					(size 1.27 1.27)
				)
				(justify mirror)
			)
		)
		(duplicate_pad_numbers_are_jumpers no)
		(fp_line
			(start 0.7874 0.4064)
			(end 0.7874 -0.04191)
			(stroke
				(width 0.1524)
				(type default)
			)
			(layer "B.SilkS")
		)
		(fp_line
			(start 0.652272 -0.4064)
			(end -0.455168 -0.4064)
			(stroke
				(width 0.1524)
				(type default)
			)
			(layer "B.SilkS")
		)
		(fp_line
			(start -0.7874 0.4064)
			(end 0.7874 0.4064)
			(stroke
				(width 0.1524)
				(type default)
			)
			(layer "B.SilkS")
		)
		(fp_line
			(start -0.7874 -0.20955)
			(end -0.7874 0.4064)
			(stroke
				(width 0.1524)
				(type default)
			)
			(layer "B.SilkS")
		)
		(fp_line
			(start 0.67945 0.3048)
			(end 0.67945 -0.305054)
			(stroke
				(width 0.1)
				(type default)
			)
			(layer "B.Fab")
		)
		(fp_line
			(start 0.67945 -0.305054)
			(end 0.12065 -0.305054)
			(stroke
				(width 0.1)
				(type default)
			)
			(layer "B.Fab")
		)
		(fp_line
			(start 0.12065 0.3048)
			(end 0.67945 0.3048)
			(stroke
				(width 0.1)
				(type default)
			)
			(layer "B.Fab")
		)
		(fp_line
			(start 0.12065 0.2794)
			(end 0.12065 0.3048)
			(stroke
				(width 0.1)
				(type default)
			)
			(layer "B.Fab")
		)
		(fp_line
			(start 0.12065 -0.2794)
			(end -0.12065 -0.2794)
			(stroke
				(width 0.1)
				(type default)
			)
			(layer "B.Fab")
		)
		(fp_line
			(start 0.12065 -0.305054)
			(end 0.12065 -0.2794)
			(stroke
				(width 0.1)
				(type default)
			)
			(layer "B.Fab")
		)
		(fp_line
			(start -0.120396 0.3048)
			(end -0.120396 0.2794)
			(stroke
				(width 0.1)
				(type default)
			)
			(layer "B.Fab")
		)
		(fp_line
			(start -0.120396 0.2794)
			(end 0.12065 0.2794)
			(stroke
				(width 0.1)
				(type default)
			)
			(layer "B.Fab")
		)
		(fp_line
			(start -0.12065 -0.2794)
			(end -0.12065 -0.3048)
			(stroke
				(width 0.1)
				(type default)
			)
			(layer "B.Fab")
		)
		(fp_line
			(start -0.12065 -0.3048)
			(end -0.67945 -0.3048)
			(stroke
				(width 0.1)
				(type default)
			)
			(layer "B.Fab")
		)
		(fp_line
			(start -0.67945 0.3048)
			(end -0.120396 0.3048)
			(stroke
				(width 0.1)
				(type default)
			)
			(layer "B.Fab")
		)
		(fp_line
			(start -0.67945 -0.3048)
			(end -0.67945 0.3048)
			(stroke
				(width 0.1)
				(type default)
			)
			(layer "B.Fab")
		)
		(pad "1" smd rect
			(at 0.40005 0 180)
			(size 0.4572 0.508)
			(layers "B.Cu" "B.Mask" "B.Paste")
			(net "CLK_25M_CK440_CPU1_R_DN")
		)
		(pad "2" smd rect
			(at -0.40005 0 180)
			(size 0.4572 0.508)
			(layers "B.Cu" "B.Mask" "B.Paste")
			(net "CLK_25M_NSSC_CPU1_DN")
		)
	)
	(footprint ""
		(layer "B.Cu")
		(at 155.356052 -196.776848 180)
		(property "Reference" "R1227"
			(at 0 0 0)
			(layer "B.SilkS")
			(hide yes)
			(effects
				(font
					(size 1.27 1.27)
				)
				(justify mirror)
			)
		)
		(property "Value" ""
			(at 0 0 0)
			(layer "B.Fab")
			(effects
				(font
					(size 1.27 1.27)
				)
				(justify mirror)
			)
		)
		(duplicate_pad_numbers_are_jumpers no)
		(fp_line
			(start 0.7874 0.4064)
			(end 0.7874 -0.4064)
			(stroke
				(width 0.1524)
				(type default)
			)
			(layer "B.SilkS")
		)
		(fp_line
			(start 0.7874 -0.4064)
			(end -0.7874 -0.4064)
			(stroke
				(width 0.1524)
				(type default)
			)
			(layer "B.SilkS")
		)
		(fp_line
			(start -0.7874 0.4064)
			(end 0.7874 0.4064)
			(stroke
				(width 0.1524)
				(type default)
			)
			(layer "B.SilkS")
		)
		(fp_line
			(start -0.7874 -0.4064)
			(end -0.7874 0.4064)
			(stroke
				(width 0.1524)
				(type default)
			)
			(layer "B.SilkS")
		)
		(fp_line
			(start 0.67945 0.3048)
			(end 0.67945 -0.305054)
			(stroke
				(width 0.1)
				(type default)
			)
			(layer "B.Fab")
		)
		(fp_line
			(start 0.67945 -0.305054)
			(end 0.12065 -0.305054)
			(stroke
				(width 0.1)
				(type default)
			)
			(layer "B.Fab")
		)
		(fp_line
			(start 0.12065 0.3048)
			(end 0.67945 0.3048)
			(stroke
				(width 0.1)
				(type default)
			)
			(layer "B.Fab")
		)
		(fp_line
			(start 0.12065 0.2794)
			(end 0.12065 0.3048)
			(stroke
				(width 0.1)
				(type default)
			)
			(layer "B.Fab")
		)
		(fp_line
			(start 0.12065 -0.2794)
			(end -0.12065 -0.2794)
			(stroke
				(width 0.1)
				(type default)
			)
			(layer "B.Fab")
		)
		(fp_line
			(start 0.12065 -0.305054)
			(end 0.12065 -0.2794)
			(stroke
				(width 0.1)
				(type default)
			)
			(layer "B.Fab")
		)
		(fp_line
			(start -0.120396 0.3048)
			(end -0.120396 0.2794)
			(stroke
				(width 0.1)
				(type default)
			)
			(layer "B.Fab")
		)
		(fp_line
			(start -0.120396 0.2794)
			(end 0.12065 0.2794)
			(stroke
				(width 0.1)
				(type default)
			)
			(layer "B.Fab")
		)
		(fp_line
			(start -0.12065 -0.2794)
			(end -0.12065 -0.3048)
			(stroke
				(width 0.1)
				(type default)
			)
			(layer "B.Fab")
		)
		(fp_line
			(start -0.12065 -0.3048)
			(end -0.67945 -0.3048)
			(stroke
				(width 0.1)
				(type default)
			)
			(layer "B.Fab")
		)
		(fp_line
			(start -0.67945 0.3048)
			(end -0.120396 0.3048)
			(stroke
				(width 0.1)
				(type default)
			)
			(layer "B.Fab")
		)
		(fp_line
			(start -0.67945 -0.3048)
			(end -0.67945 0.3048)
			(stroke
				(width 0.1)
				(type default)
			)
			(layer "B.Fab")
		)
		(pad "1" smd circle
			(at 0.40005 0)
			(size 0 0)
			(layers "B.Cu" "B.Mask" "B.Paste")
			(net "PD_JTAG_CPU1_PLD_TCK")
		)
		(pad "2" smd circle
			(at -0.40005 0)
			(size 0 0)
			(layers "B.Cu" "B.Mask" "B.Paste")
			(net "GND")
		)
	)
)
